(kicad_pcb
	(version 20260206)
	(generator "pcbnew")
	(generator_version "10.0")
	(general
		(thickness 1.6)
		(legacy_teardrops no)
	)
	(paper "A4")
	(title_block
		(title "04192023_DAF0TMB3IC0_F0TG_MB_C_brd_V02_OCP.brd")
		(comment 1 "Grand Teton / footprints 5250-5256 of 8354")
	)
	(layers
		(0 "F.Cu" signal "TOP")
		(4 "In1.Cu" signal "GND")
		(6 "In2.Cu" signal "IN1")
		(8 "In3.Cu" signal "GND1")
		(10 "In4.Cu" signal "IN2")
		(12 "In5.Cu" signal "GND2")
		(14 "In6.Cu" signal "IN3")
		(16 "In7.Cu" signal "GND3")
		(18 "In8.Cu" signal "VCC")
		(20 "In9.Cu" signal "VCC1")
		(22 "In10.Cu" signal "GND4")
		(24 "In11.Cu" signal "IN4")
		(26 "In12.Cu" signal "GND5")
		(28 "In13.Cu" signal "IN5")
		(30 "In14.Cu" signal "GND6")
		(32 "In15.Cu" signal "IN6")
		(34 "In16.Cu" signal "GND7")
		(2 "B.Cu" signal "BOTTOM")
		(9 "F.Adhes" user "F.Adhesive")
		(11 "B.Adhes" user "B.Adhesive")
		(13 "F.Paste" user "Package Geometry/Pastemask Top")
		(15 "B.Paste" user "Package Geometry/Pastemask Bottom")
		(5 "F.SilkS" user "Ref Des/Silkscreen Top")
		(7 "B.SilkS" user "Ref Des/Silkscreen Bottom")
		(1 "F.Mask" user "Board Geometry/Soldermask Top")
		(3 "B.Mask" user "Board Geometry/Soldermask Bottom")
		(17 "Dwgs.User" user "User.Drawings")
		(19 "Cmts.User" user "User.Comments")
		(21 "Eco1.User" user "User.Eco1")
		(23 "Eco2.User" user "User.Eco2")
		(25 "Edge.Cuts" user "Board Geometry/Outline")
		(27 "Margin" user)
		(31 "F.CrtYd" user "Package Geometry/Place Bound Top")
		(29 "B.CrtYd" user "Package Geometry/Place Bound Bottom")
		(35 "F.Fab" user "Ref Des/Assembly Top")
		(33 "B.Fab" user "Ref Des/Assembly Bottom")
	)
	(footprint ""
		(layer "B.Cu")
		(at 393.617958 -324.862952)
		(property "Reference" "R470"
			(at 0 0 0)
			(layer "B.SilkS")
			(hide yes)
			(effects
				(font
					(size 1.27 1.27)
				)
				(justify mirror)
			)
		)
		(property "Value" ""
			(at 0 0 0)
			(layer "B.Fab")
			(effects
				(font
					(size 1.27 1.27)
				)
				(justify mirror)
			)
		)
		(duplicate_pad_numbers_are_jumpers no)
		(fp_line
			(start -0.7874 -0.4064)
			(end -0.7874 0.4064)
			(stroke
				(width 0.1524)
				(type default)
			)
			(layer "B.SilkS")
		)
		(fp_line
			(start -0.7874 0.4064)
			(end 0.7874 0.4064)
			(stroke
				(width 0.1524)
				(type default)
			)
			(layer "B.SilkS")
		)
		(fp_line
			(start 0.7874 -0.4064)
			(end -0.7874 -0.4064)
			(stroke
				(width 0.1524)
				(type default)
			)
			(layer "B.SilkS")
		)
		(fp_line
			(start 0.7874 0.4064)
			(end 0.7874 -0.4064)
			(stroke
				(width 0.1524)
				(type default)
			)
			(layer "B.SilkS")
		)
		(fp_line
			(start -0.67945 -0.3048)
			(end -0.67945 0.3048)
			(stroke
				(width 0.1)
				(type default)
			)
			(layer "B.Fab")
		)
		(fp_line
			(start -0.67945 0.3048)
			(end -0.120396 0.3048)
			(stroke
				(width 0.1)
				(type default)
			)
			(layer "B.Fab")
		)
		(fp_line
			(start -0.12065 -0.3048)
			(end -0.67945 -0.3048)
			(stroke
				(width 0.1)
				(type default)
			)
			(layer "B.Fab")
		)
		(fp_line
			(start -0.12065 -0.2794)
			(end -0.12065 -0.3048)
			(stroke
				(width 0.1)
				(type default)
			)
			(layer "B.Fab")
		)
		(fp_line
			(start -0.120396 0.2794)
			(end 0.12065 0.2794)
			(stroke
				(width 0.1)
				(type default)
			)
			(layer "B.Fab")
		)
		(fp_line
			(start -0.120396 0.3048)
			(end -0.120396 0.2794)
			(stroke
				(width 0.1)
				(type default)
			)
			(layer "B.Fab")
		)
		(fp_line
			(start 0.12065 -0.305054)
			(end 0.12065 -0.2794)
			(stroke
				(width 0.1)
				(type default)
			)
			(layer "B.Fab")
		)
		(fp_line
			(start 0.12065 -0.2794)
			(end -0.12065 -0.2794)
			(stroke
				(width 0.1)
				(type default)
			)
			(layer "B.Fab")
		)
		(fp_line
			(start 0.12065 0.2794)
			(end 0.12065 0.3048)
			(stroke
				(width 0.1)
				(type default)
			)
			(layer "B.Fab")
		)
		(fp_line
			(start 0.12065 0.3048)
			(end 0.67945 0.3048)
			(stroke
				(width 0.1)
				(type default)
			)
			(layer "B.Fab")
		)
		(fp_line
			(start 0.67945 -0.305054)
			(end 0.12065 -0.305054)
			(stroke
				(width 0.1)
				(type default)
			)
			(layer "B.Fab")
		)
		(fp_line
			(start 0.67945 0.3048)
			(end 0.67945 -0.305054)
			(stroke
				(width 0.1)
				(type default)
			)
			(layer "B.Fab")
		)
		(pad "1" smd circle
			(at 0.40005 0 180)
			(size 0 0)
			(layers "B.Cu" "B.Mask" "B.Paste")
			(net "ESPI_CPU0_D2")
		)
		(pad "2" smd circle
			(at -0.40005 0 180)
			(size 0 0)
			(layers "B.Cu" "B.Mask" "B.Paste")
			(net "ESPI_CPU0_R_D2")
		)
	)
	(footprint ""
		(layer "B.Cu")
		(at 280.492454 -190.94831 180)
		(property "Reference" "R294"
			(at 0 0 0)
			(layer "B.SilkS")
			(hide yes)
			(effects
				(font
					(size 1.27 1.27)
				)
				(justify mirror)
			)
		)
		(property "Value" ""
			(at 0 0 0)
			(layer "B.Fab")
			(effects
				(font
					(size 1.27 1.27)
				)
				(justify mirror)
			)
		)
		(duplicate_pad_numbers_are_jumpers no)
		(fp_line
			(start 0.7874 0.4064)
			(end 0.7874 -0.4064)
			(stroke
				(width 0.1524)
				(type default)
			)
			(layer "B.SilkS")
		)
		(fp_line
			(start 0.7874 -0.4064)
			(end -0.7874 -0.4064)
			(stroke
				(width 0.1524)
				(type default)
			)
			(layer "B.SilkS")
		)
		(fp_line
			(start -0.7874 0.4064)
			(end 0.7874 0.4064)
			(stroke
				(width 0.1524)
				(type default)
			)
			(layer "B.SilkS")
		)
		(fp_line
			(start -0.7874 -0.4064)
			(end -0.7874 0.4064)
			(stroke
				(width 0.1524)
				(type default)
			)
			(layer "B.SilkS")
		)
		(fp_line
			(start 0.67945 0.3048)
			(end 0.67945 -0.305054)
			(stroke
				(width 0.1)
				(type default)
			)
			(layer "B.Fab")
		)
		(fp_line
			(start 0.67945 -0.305054)
			(end 0.12065 -0.305054)
			(stroke
				(width 0.1)
				(type default)
			)
			(layer "B.Fab")
		)
		(fp_line
			(start 0.12065 0.3048)
			(end 0.67945 0.3048)
			(stroke
				(width 0.1)
				(type default)
			)
			(layer "B.Fab")
		)
		(fp_line
			(start 0.12065 0.2794)
			(end 0.12065 0.3048)
			(stroke
				(width 0.1)
				(type default)
			)
			(layer "B.Fab")
		)
		(fp_line
			(start 0.12065 -0.2794)
			(end -0.12065 -0.2794)
			(stroke
				(width 0.1)
				(type default)
			)
			(layer "B.Fab")
		)
		(fp_line
			(start 0.12065 -0.305054)
			(end 0.12065 -0.2794)
			(stroke
				(width 0.1)
				(type default)
			)
			(layer "B.Fab")
		)
		(fp_line
			(start -0.120396 0.3048)
			(end -0.120396 0.2794)
			(stroke
				(width 0.1)
				(type default)
			)
			(layer "B.Fab")
		)
		(fp_line
			(start -0.120396 0.2794)
			(end 0.12065 0.2794)
			(stroke
				(width 0.1)
				(type default)
			)
			(layer "B.Fab")
		)
		(fp_line
			(start -0.12065 -0.2794)
			(end -0.12065 -0.3048)
			(stroke
				(width 0.1)
				(type default)
			)
			(layer "B.Fab")
		)
		(fp_line
			(start -0.12065 -0.3048)
			(end -0.67945 -0.3048)
			(stroke
				(width 0.1)
				(type default)
			)
			(layer "B.Fab")
		)
		(fp_line
			(start -0.67945 0.3048)
			(end -0.120396 0.3048)
			(stroke
				(width 0.1)
				(type default)
			)
			(layer "B.Fab")
		)
		(fp_line
			(start -0.67945 -0.3048)
			(end -0.67945 0.3048)
			(stroke
				(width 0.1)
				(type default)
			)
			(layer "B.Fab")
		)
		(pad "1" smd circle
			(at 0.40005 0)
			(size 0 0)
			(layers "B.Cu" "B.Mask" "B.Paste")
			(net "PWRGD_CHD_CPU0_DIMM")
		)
		(pad "2" smd circle
			(at -0.40005 0)
			(size 0 0)
			(layers "B.Cu" "B.Mask" "B.Paste")
			(net "PWRGD_CHAF_CPU0")
		)
	)
	(footprint ""
		(layer "B.Cu")
		(at 81.257648 -182.656734 -90)
		(property "Reference" "PC266_1"
			(at 0 0 90)
			(layer "B.SilkS")
			(hide yes)
			(effects
				(font
					(size 1.27 1.27)
				)
				(justify mirror)
			)
		)
		(property "Value" ""
			(at 0 0 90)
			(layer "B.Fab")
			(effects
				(font
					(size 1.27 1.27)
				)
				(justify mirror)
			)
		)
		(duplicate_pad_numbers_are_jumpers no)
		(fp_line
			(start -1.524 0.762)
			(end 1.524 0.762)
			(stroke
				(width 0.1524)
				(type default)
			)
			(layer "B.SilkS")
		)
		(fp_line
			(start 1.524 0.762)
			(end 1.524 -0.762)
			(stroke
				(width 0.1524)
				(type default)
			)
			(layer "B.SilkS")
		)
		(fp_line
			(start -1.524 -0.762)
			(end -1.524 0.762)
			(stroke
				(width 0.1524)
				(type default)
			)
			(layer "B.SilkS")
		)
		(fp_line
			(start 1.524 -0.762)
			(end -1.524 -0.762)
			(stroke
				(width 0.1524)
				(type default)
			)
			(layer "B.SilkS")
		)
		(fp_line
			(start -1.1049 0.724916)
			(end -1.1049 -0.724916)
			(stroke
				(width 0.1)
				(type default)
			)
			(layer "B.Fab")
		)
		(fp_line
			(start 1.1049 0.724916)
			(end -1.1049 0.724916)
			(stroke
				(width 0.1)
				(type default)
			)
			(layer "B.Fab")
		)
		(fp_line
			(start -1.1049 -0.724916)
			(end 1.1049 -0.724916)
			(stroke
				(width 0.1)
				(type default)
			)
			(layer "B.Fab")
		)
		(fp_line
			(start 1.1049 -0.724916)
			(end 1.1049 0.724916)
			(stroke
				(width 0.1)
				(type default)
			)
			(layer "B.Fab")
		)
		(pad "1" smd rect
			(at 0.889 0 270)
			(size 1.016 1.27)
			(layers "B.Cu" "B.Mask" "B.Paste")
			(net "SW_P12V_AUX_PVDDCR_CPU0_P1_FLT")
		)
		(pad "2" smd rect
			(at -0.889 0 270)
			(size 1.016 1.27)
			(layers "B.Cu" "B.Mask" "B.Paste")
			(net "GND")
		)
	)
	(footprint ""
		(layer "B.Cu")
		(at 374.986042 -181.684676 90)
		(property "Reference" "PR319"
			(at 0 0 90)
			(layer "B.SilkS")
			(hide yes)
			(effects
				(font
					(size 1.27 1.27)
				)
				(justify mirror)
			)
		)
		(property "Value" ""
			(at 0 0 90)
			(layer "B.Fab")
			(effects
				(font
					(size 1.27 1.27)
				)
				(justify mirror)
			)
		)
		(duplicate_pad_numbers_are_jumpers no)
		(fp_line
			(start 0.7874 -0.4064)
			(end -0.7874 -0.4064)
			(stroke
				(width 0.1524)
				(type default)
			)
			(layer "B.SilkS")
		)
		(fp_line
			(start -0.7874 -0.4064)
			(end -0.7874 0.4064)
			(stroke
				(width 0.1524)
				(type default)
			)
			(layer "B.SilkS")
		)
		(fp_line
			(start 0.7874 0.4064)
			(end 0.7874 -0.4064)
			(stroke
				(width 0.1524)
				(type default)
			)
			(layer "B.SilkS")
		)
		(fp_line
			(start -0.7874 0.4064)
			(end 0.7874 0.4064)
			(stroke
				(width 0.1524)
				(type default)
			)
			(layer "B.SilkS")
		)
		(fp_line
			(start 0.67945 -0.305054)
			(end 0.12065 -0.305054)
			(stroke
				(width 0.1)
				(type default)
			)
			(layer "B.Fab")
		)
		(fp_line
			(start 0.12065 -0.305054)
			(end 0.12065 -0.2794)
			(stroke
				(width 0.1)
				(type default)
			)
			(layer "B.Fab")
		)
		(fp_line
			(start -0.12065 -0.3048)
			(end -0.67945 -0.3048)
			(stroke
				(width 0.1)
				(type default)
			)
			(layer "B.Fab")
		)
		(fp_line
			(start -0.67945 -0.3048)
			(end -0.67945 0.3048)
			(stroke
				(width 0.1)
				(type default)
			)
			(layer "B.Fab")
		)
		(fp_line
			(start 0.12065 -0.2794)
			(end -0.12065 -0.2794)
			(stroke
				(width 0.1)
				(type default)
			)
			(layer "B.Fab")
		)
		(fp_line
			(start -0.12065 -0.2794)
			(end -0.12065 -0.3048)
			(stroke
				(width 0.1)
				(type default)
			)
			(layer "B.Fab")
		)
		(fp_line
			(start 0.12065 0.2794)
			(end 0.12065 0.3048)
			(stroke
				(width 0.1)
				(type default)
			)
			(layer "B.Fab")
		)
		(fp_line
			(start -0.120396 0.2794)
			(end 0.12065 0.2794)
			(stroke
				(width 0.1)
				(type default)
			)
			(layer "B.Fab")
		)
		(fp_line
			(start 0.67945 0.3048)
			(end 0.67945 -0.305054)
			(stroke
				(width 0.1)
				(type default)
			)
			(layer "B.Fab")
		)
		(fp_line
			(start 0.12065 0.3048)
			(end 0.67945 0.3048)
			(stroke
				(width 0.1)
				(type default)
			)
			(layer "B.Fab")
		)
		(fp_line
			(start -0.120396 0.3048)
			(end -0.120396 0.2794)
			(stroke
				(width 0.1)
				(type default)
			)
			(layer "B.Fab")
		)
		(fp_line
			(start -0.67945 0.3048)
			(end -0.120396 0.3048)
			(stroke
				(width 0.1)
				(type default)
			)
			(layer "B.Fab")
		)
		(pad "1" smd circle
			(at 0.40005 0 270)
			(size 0 0)
			(layers "B.Cu" "B.Mask" "B.Paste")
			(net "PVDDCR_CPU0_P0_PVCC")
		)
		(pad "2" smd circle
			(at -0.40005 0 270)
			(size 0 0)
			(layers "B.Cu" "B.Mask" "B.Paste")
			(net "PVDDCR_CPU0_P0_VCC2")
		)
	)
	(footprint ""
		(layer "B.Cu")
		(at 101.033834 -250.892564 180)
		(property "Reference" "C2673"
			(at 0 0 0)
			(layer "B.SilkS")
			(hide yes)
			(effects
				(font
					(size 1.27 1.27)
				)
				(justify mirror)
			)
		)
		(property "Value" ""
			(at 0 0 0)
			(layer "B.Fab")
			(effects
				(font
					(size 1.27 1.27)
				)
				(justify mirror)
			)
		)
		(duplicate_pad_numbers_are_jumpers no)
		(fp_line
			(start 0.7874 0.4064)
			(end 0.7874 -0.4064)
			(stroke
				(width 0.1524)
				(type default)
			)
			(layer "B.SilkS")
		)
		(fp_line
			(start 0.7874 -0.4064)
			(end -0.7874 -0.4064)
			(stroke
				(width 0.1524)
				(type default)
			)
			(layer "B.SilkS")
		)
		(fp_line
			(start -0.7874 0.4064)
			(end 0.7874 0.4064)
			(stroke
				(width 0.1524)
				(type default)
			)
			(layer "B.SilkS")
		)
		(fp_line
			(start -0.7874 -0.4064)
			(end -0.7874 0.4064)
			(stroke
				(width 0.1524)
				(type default)
			)
			(layer "B.SilkS")
		)
		(fp_line
			(start 0.67945 0.3048)
			(end 0.67945 -0.305054)
			(stroke
				(width 0.1)
				(type default)
			)
			(layer "B.Fab")
		)
		(fp_line
			(start 0.67945 -0.305054)
			(end 0.12065 -0.305054)
			(stroke
				(width 0.1)
				(type default)
			)
			(layer "B.Fab")
		)
		(fp_line
			(start 0.12065 0.3048)
			(end 0.67945 0.3048)
			(stroke
				(width 0.1)
				(type default)
			)
			(layer "B.Fab")
		)
		(fp_line
			(start 0.12065 0.2794)
			(end 0.12065 0.3048)
			(stroke
				(width 0.1)
				(type default)
			)
			(layer "B.Fab")
		)
		(fp_line
			(start 0.12065 -0.2794)
			(end -0.12065 -0.2794)
			(stroke
				(width 0.1)
				(type default)
			)
			(layer "B.Fab")
		)
		(fp_line
			(start 0.12065 -0.305054)
			(end 0.12065 -0.2794)
			(stroke
				(width 0.1)
				(type default)
			)
			(layer "B.Fab")
		)
		(fp_line
			(start -0.120396 0.3048)
			(end -0.120396 0.2794)
			(stroke
				(width 0.1)
				(type default)
			)
			(layer "B.Fab")
		)
		(fp_line
			(start -0.120396 0.2794)
			(end 0.12065 0.2794)
			(stroke
				(width 0.1)
				(type default)
			)
			(layer "B.Fab")
		)
		(fp_line
			(start -0.12065 -0.2794)
			(end -0.12065 -0.3048)
			(stroke
				(width 0.1)
				(type default)
			)
			(layer "B.Fab")
		)
		(fp_line
			(start -0.12065 -0.3048)
			(end -0.67945 -0.3048)
			(stroke
				(width 0.1)
				(type default)
			)
			(layer "B.Fab")
		)
		(fp_line
			(start -0.67945 0.3048)
			(end -0.120396 0.3048)
			(stroke
				(width 0.1)
				(type default)
			)
			(layer "B.Fab")
		)
		(fp_line
			(start -0.67945 -0.3048)
			(end -0.67945 0.3048)
			(stroke
				(width 0.1)
				(type default)
			)
			(layer "B.Fab")
		)
		(pad "1" smd circle
			(at 0.40005 0)
			(size 0 0)
			(layers "B.Cu" "B.Mask" "B.Paste")
			(net "PVDD18_S5_P1")
		)
		(pad "2" smd circle
			(at -0.40005 0)
			(size 0 0)
			(layers "B.Cu" "B.Mask" "B.Paste")
			(net "GND")
		)
	)
	(footprint ""
		(layer "B.Cu")
		(at 214.884 -332.74)
		(property "Reference" "R6778"
			(at 0 0 0)
			(layer "B.SilkS")
			(hide yes)
			(effects
				(font
					(size 1.27 1.27)
				)
				(justify mirror)
			)
		)
		(property "Value" ""
			(at 0 0 0)
			(layer "B.Fab")
			(effects
				(font
					(size 1.27 1.27)
				)
				(justify mirror)
			)
		)
		(duplicate_pad_numbers_are_jumpers no)
		(fp_line
			(start -0.32512 -0.175006)
			(end -0.32512 0.175006)
			(stroke
				(width 0.1)
				(type default)
			)
			(layer "B.Fab")
		)
		(fp_line
			(start -0.32512 0.175006)
			(end 0.32512 0.175006)
			(stroke
				(width 0.1)
				(type default)
			)
			(layer "B.Fab")
		)
		(fp_line
			(start 0.32512 -0.175006)
			(end -0.32512 -0.175006)
			(stroke
				(width 0.1)
				(type default)
			)
			(layer "B.Fab")
		)
		(fp_line
			(start 0.32512 0.175006)
			(end 0.32512 -0.175006)
			(stroke
				(width 0.1)
				(type default)
			)
			(layer "B.Fab")
		)
		(pad "1" smd rect
			(at 0.2667 0 180)
			(size 0.3048 0.381)
			(layers "B.Cu" "B.Mask" "B.Paste")
			(net "RST_SMB_RT_R1_N")
		)
		(pad "2" smd rect
			(at -0.2667 0)
			(size 0.3048 0.381)
			(layers "B.Cu" "B.Mask" "B.Paste")
			(net "GND")
		)
	)
	(footprint ""
		(layer "B.Cu")
		(at 341.475314 -310.974486)
		(property "Reference" "PR59"
			(at 0 0 0)
			(layer "B.SilkS")
			(hide yes)
			(effects
				(font
					(size 1.27 1.27)
				)
				(justify mirror)
			)
		)
		(property "Value" ""
			(at 0 0 0)
			(layer "B.Fab")
			(effects
				(font
					(size 1.27 1.27)
				)
				(justify mirror)
			)
		)
		(duplicate_pad_numbers_are_jumpers no)
		(fp_line
			(start -0.7874 -0.4064)
			(end -0.7874 0.4064)
			(stroke
				(width 0.1524)
				(type default)
			)
			(layer "B.SilkS")
		)
		(fp_line
			(start -0.7874 0.4064)
			(end 0.7874 0.4064)
			(stroke
				(width 0.1524)
				(type default)
			)
			(layer "B.SilkS")
		)
		(fp_line
			(start 0.7874 -0.4064)
			(end -0.7874 -0.4064)
			(stroke
				(width 0.1524)
				(type default)
			)
			(layer "B.SilkS")
		)
		(fp_line
			(start 0.7874 0.4064)
			(end 0.7874 -0.4064)
			(stroke
				(width 0.1524)
				(type default)
			)
			(layer "B.SilkS")
		)
		(fp_line
			(start -0.67945 -0.3048)
			(end -0.67945 0.3048)
			(stroke
				(width 0.1)
				(type default)
			)
			(layer "B.Fab")
		)
		(fp_line
			(start -0.67945 0.3048)
			(end -0.120396 0.3048)
			(stroke
				(width 0.1)
				(type default)
			)
			(layer "B.Fab")
		)
		(fp_line
			(start -0.12065 -0.3048)
			(end -0.67945 -0.3048)
			(stroke
				(width 0.1)
				(type default)
			)
			(layer "B.Fab")
		)
		(fp_line
			(start -0.12065 -0.2794)
			(end -0.12065 -0.3048)
			(stroke
				(width 0.1)
				(type default)
			)
			(layer "B.Fab")
		)
		(fp_line
			(start -0.120396 0.2794)
			(end 0.12065 0.2794)
			(stroke
				(width 0.1)
				(type default)
			)
			(layer "B.Fab")
		)
		(fp_line
			(start -0.120396 0.3048)
			(end -0.120396 0.2794)
			(stroke
				(width 0.1)
				(type default)
			)
			(layer "B.Fab")
		)
		(fp_line
			(start 0.12065 -0.305054)
			(end 0.12065 -0.2794)
			(stroke
				(width 0.1)
				(type default)
			)
			(layer "B.Fab")
		)
		(fp_line
			(start 0.12065 -0.2794)
			(end -0.12065 -0.2794)
			(stroke
				(width 0.1)
				(type default)
			)
			(layer "B.Fab")
		)
		(fp_line
			(start 0.12065 0.2794)
			(end 0.12065 0.3048)
			(stroke
				(width 0.1)
				(type default)
			)
			(layer "B.Fab")
		)
		(fp_line
			(start 0.12065 0.3048)
			(end 0.67945 0.3048)
			(stroke
				(width 0.1)
				(type default)
			)
			(layer "B.Fab")
		)
		(fp_line
			(start 0.67945 -0.305054)
			(end 0.12065 -0.305054)
			(stroke
				(width 0.1)
				(type default)
			)
			(layer "B.Fab")
		)
		(fp_line
			(start 0.67945 0.3048)
			(end 0.67945 -0.305054)
			(stroke
				(width 0.1)
				(type default)
			)
			(layer "B.Fab")
		)
		(pad "1" smd circle
			(at 0.40005 0 180)
			(size 0 0)
			(layers "B.Cu" "B.Mask" "B.Paste")
			(net "SVID_PVDDCR_CPU1_P0_SVC_R")
		)
		(pad "2" smd circle
			(at -0.40005 0 180)
			(size 0 0)
			(layers "B.Cu" "B.Mask" "B.Paste")
			(net "SVID_PVDDCR_CPU1_P0_SVC")
		)
	)
)
